(kicad_pcb
	(version 20240108)
	(generator "pcbnew")
	(generator_version "8.0")
	(general
		(thickness 1.62)
		(legacy_teardrops no)
	)
	(paper "A4")
	(title_block
		(title "Jetson Orin Baseboard")
		(date "2025-03-12")
		(rev "1.3.4")
		(company "Antmicro Ltd")
		(comment 1 "www.antmicro.com")
		(comment 9 "footprints 43-47 of 677")
	)
	(layers
		(0 "F.Cu" signal)
		(1 "In1.Cu" signal)
		(2 "In2.Cu" signal)
		(3 "In3.Cu" signal)
		(4 "In4.Cu" jumper)
		(5 "In5.Cu" signal)
		(6 "In6.Cu" signal)
		(31 "B.Cu" signal)
		(32 "B.Adhes" user "B.Adhesive")
		(33 "F.Adhes" user "F.Adhesive")
		(34 "B.Paste" user)
		(35 "F.Paste" user)
		(36 "B.SilkS" user "B.Silkscreen")
		(37 "F.SilkS" user "F.Silkscreen")
		(38 "B.Mask" user)
		(39 "F.Mask" user)
		(40 "Dwgs.User" user "User.Drawings")
		(41 "Cmts.User" user "User.Comments")
		(42 "Eco1.User" user "User.Eco1")
		(43 "Eco2.User" user "User.Eco2")
		(44 "Edge.Cuts" user)
		(45 "Margin" user)
		(46 "B.CrtYd" user "B.Courtyard")
		(47 "F.CrtYd" user "F.Courtyard")
		(48 "B.Fab" user)
		(49 "F.Fab" user)
	)
	(footprint "antmicro-footprints:SOT-523"
		(layer "F.Cu")
		(at 92.85 93.9 180)
		(property "Reference" "Q3"
			(at -2.05 -0.68 -90)
			(layer "F.SilkS")
			(effects
				(font
					(size 0.7 0.7)
					(thickness 0.15)
				)
				(justify left bottom)
			)
		)
		(property "Value" "PJE138K"
			(at 0.1 1.824 180)
			(layer "F.Fab")
			(effects
				(font
					(size 0.7 0.7)
					(thickness 0.15)
				)
				(justify left bottom)
			)
		)
		(property "Footprint" "antmicro-footprints:SOT-523"
			(at 0 0 180)
			(layer "F.Fab")
			(hide yes)
			(effects
				(font
					(size 1.27 1.27)
					(thickness 0.15)
				)
			)
		)
		(property "Datasheet" "https://www.mouser.com/datasheet/2/1057/PJE138K-1876698.pdf"
			(at 0 0 180)
			(layer "F.Fab")
			(hide yes)
			(effects
				(font
					(size 1.27 1.27)
					(thickness 0.15)
				)
			)
		)
		(property "Author" "Antmicro"
			(at 185.7 187.8 0)
			(layer "F.Fab")
			(hide yes)
			(effects
				(font
					(size 1 1)
					(thickness 0.15)
				)
			)
		)
		(property "License" "Apache-2.0"
			(at 185.7 187.8 0)
			(layer "F.Fab")
			(hide yes)
			(effects
				(font
					(size 1 1)
					(thickness 0.15)
				)
			)
		)
		(property "MPN" "PJE138K_R1_00001"
			(at 185.7 187.8 0)
			(layer "F.Fab")
			(hide yes)
			(effects
				(font
					(size 1 1)
					(thickness 0.15)
				)
			)
		)
		(property "Manufacturer" "PANJIT"
			(at 185.7 187.8 0)
			(layer "F.Fab")
			(hide yes)
			(effects
				(font
					(size 1 1)
					(thickness 0.15)
				)
			)
		)
		(sheetname "HDMI")
		(sheetfile "hdmi.kicad_sch")
		(attr smd exclude_from_pos_files exclude_from_bom dnp)
		(fp_line
			(start -0.277 -0.551)
			(end -0.277 -0.75)
			(stroke
				(width 0.15)
				(type solid)
			)
			(layer "F.SilkS")
		)
		(fp_line
			(start -0.725 -0.551)
			(end -0.277 -0.551)
			(stroke
				(width 0.15)
				(type solid)
			)
			(layer "F.SilkS")
		)
		(fp_line
			(start -0.927 -0.051)
			(end -0.927 -0.351)
			(stroke
				(width 0.15)
				(type solid)
			)
			(layer "F.SilkS")
		)
		(fp_line
			(start -0.927 -0.351)
			(end -0.725 -0.551)
			(stroke
				(width 0.15)
				(type solid)
			)
			(layer "F.SilkS")
		)
		(fp_circle
			(center -0.9652 0.9652)
			(end -0.9152 0.9652)
			(stroke
				(width 0.15)
				(type solid)
			)
			(fill solid)
			(layer "F.SilkS")
		)
		(fp_line
			(start 1.1 -1.16)
			(end 1.1 1.15)
			(stroke
				(width 0.05)
				(type solid)
			)
			(layer "F.CrtYd")
		)
		(fp_line
			(start -1.12 1.15)
			(end 1.1 1.15)
			(stroke
				(width 0.05)
				(type solid)
			)
			(layer "F.CrtYd")
		)
		(fp_line
			(start -1.12 -1.16)
			(end 1.1 -1.16)
			(stroke
				(width 0.05)
				(type solid)
			)
			(layer "F.CrtYd")
		)
		(fp_line
			(start -1.12 -1.16)
			(end -1.12 1.15)
			(stroke
				(width 0.05)
				(type solid)
			)
			(layer "F.CrtYd")
		)
		(fp_line
			(start 0.8 0.424)
			(end -0.802 0.424)
			(stroke
				(width 0.15)
				(type solid)
			)
			(layer "F.Fab")
		)
		(fp_line
			(start 0.8 -0.425)
			(end 0.8 0.424)
			(stroke
				(width 0.15)
				(type solid)
			)
			(layer "F.Fab")
		)
		(fp_line
			(start 0.8 -0.425)
			(end -0.652 -0.425)
			(stroke
				(width 0.15)
				(type solid)
			)
			(layer "F.Fab")
		)
		(fp_line
			(start -0.652 -0.425)
			(end -0.802 -0.276)
			(stroke
				(width 0.15)
				(type solid)
			)
			(layer "F.Fab")
		)
		(fp_line
			(start -0.802 -0.276)
			(end -0.802 0.424)
			(stroke
				(width 0.15)
				(type solid)
			)
			(layer "F.Fab")
		)
		(fp_circle
			(center -0.9652 0.9652)
			(end -0.9144 0.9652)
			(stroke
				(width 0.15)
				(type solid)
			)
			(fill none)
			(layer "F.Fab")
		)
		(fp_text user "${REFERENCE}"
			(at -1.12 3.824 180)
			(layer "F.Fab")
			(hide yes)
			(effects
				(font
					(size 0.7 0.7)
					(thickness 0.15)
				)
				(justify left bottom)
			)
		)
		(fp_text user "License: Apache-2.0"
			(at -1.12 5.024 180)
			(layer "F.Fab")
			(hide yes)
			(effects
				(font
					(size 0.7 0.7)
					(thickness 0.15)
				)
				(justify left bottom)
			)
		)
		(fp_text user "Author: Antmicro"
			(at -1.12 6.224 180)
			(layer "F.Fab")
			(hide yes)
			(effects
				(font
					(size 0.7 0.7)
					(thickness 0.15)
				)
				(justify left bottom)
			)
		)
		(pad "1" smd rect
			(at -0.5 0.65 180)
			(size 0.4 0.51)
			(layers "F.Cu" "F.Paste" "F.Mask")
			(net 677 "USBC_HPD")
			(pinfunction "G")
			(pintype "passive")
		)
		(pad "2" smd rect
			(at 0.498 0.65 180)
			(size 0.4 0.51)
			(layers "F.Cu" "F.Paste" "F.Mask")
			(net 1 "GND")
			(pinfunction "S")
			(pintype "passive")
		)
		(pad "3" smd rect
			(at 0 -0.652 180)
			(size 0.4 0.51)
			(layers "F.Cu" "F.Paste" "F.Mask")
			(net 624 "Net-(Q3-D)")
			(pinfunction "D")
			(pintype "passive")
		)
	)
	(footprint "antmicro-footprints:TP_SMD_0.75mm"
		(layer "F.Cu")
		(at 104.1 82.25)
		(property "Reference" "TP35"
			(at 0.225 0.425 0)
			(layer "F.SilkS")
			(effects
				(font
					(size 0.7 0.7)
					(thickness 0.15)
				)
				(justify left bottom)
			)
		)
		(property "Value" "TP_0.75mm_SMD"
			(at 0 1.2 0)
			(layer "F.Fab")
			(effects
				(font
					(size 0.7 0.7)
					(thickness 0.15)
				)
				(justify left bottom)
			)
		)
		(property "Footprint" "antmicro-footprints:TP_SMD_0.75mm"
			(at 0 0 0)
			(layer "F.Fab")
			(hide yes)
			(effects
				(font
					(size 1.27 1.27)
					(thickness 0.15)
				)
			)
		)
		(property "Author" "Antmicro"
			(at 0 0 0)
			(layer "F.Fab")
			(hide yes)
			(effects
				(font
					(size 1 1)
					(thickness 0.15)
				)
			)
		)
		(property "License" "Apache-2.0"
			(at 0 0 0)
			(layer "F.Fab")
			(hide yes)
			(effects
				(font
					(size 1 1)
					(thickness 0.15)
				)
			)
		)
		(property "MPN" ""
			(at 0 0 0)
			(layer "F.Fab")
			(hide yes)
			(effects
				(font
					(size 1 1)
					(thickness 0.15)
				)
			)
		)
		(property "Manufacturer" ""
			(at 0 0 0)
			(layer "F.Fab")
			(hide yes)
			(effects
				(font
					(size 1 1)
					(thickness 0.15)
				)
			)
		)
		(sheetname "SoM")
		(sheetfile "som.kicad_sch")
		(attr exclude_from_pos_files exclude_from_bom)
		(fp_circle
			(center 0 0)
			(end 0.475 0)
			(stroke
				(width 0.05)
				(type default)
			)
			(fill none)
			(layer "F.CrtYd")
		)
		(fp_text user "License: Apache-2.0"
			(at -0.4 5.101 0)
			(layer "F.Fab")
			(hide yes)
			(effects
				(font
					(size 0.7 0.7)
					(thickness 0.15)
				)
				(justify left bottom)
			)
		)
		(fp_text user "Author: Antmicro"
			(at -0.4 3.901 0)
			(layer "F.Fab")
			(hide yes)
			(effects
				(font
					(size 0.7 0.7)
					(thickness 0.15)
				)
				(justify left bottom)
			)
		)
		(fp_text user "${REFERENCE}"
			(at -0.4 2.7 0)
			(layer "F.Fab")
			(hide yes)
			(effects
				(font
					(size 0.7 0.7)
					(thickness 0.15)
				)
				(justify left bottom)
			)
		)
		(pad "1" smd circle
			(at 0 0)
			(size 0.75 0.75)
			(layers "F.Cu" "F.Mask")
			(net 742 "Net-(J15E-HDMI_CEC)")
			(pinfunction "1")
			(pintype "passive")
		)
	)
	(footprint "antmicro-footprints:XDFN-2_1x0.60mm"
		(layer "F.Cu")
		(at 130.19 123.34 90)
		(property "Reference" "D56"
			(at 0.69 -1.24 -90)
			(layer "F.SilkS")
			(effects
				(font
					(size 0.7 0.7)
					(thickness 0.15)
				)
				(justify left bottom)
			)
		)
		(property "Value" "TPD1E0B04_XDFN-2"
			(at 0 1.5 90)
			(layer "F.Fab")
			(effects
				(font
					(size 0.7 0.7)
					(thickness 0.15)
				)
				(justify left bottom)
			)
		)
		(property "Footprint" "antmicro-footprints:XDFN-2_1x0.60mm"
			(at 0 0 90)
			(layer "F.Fab")
			(hide yes)
			(effects
				(font
					(size 1.27 1.27)
					(thickness 0.15)
				)
			)
		)
		(property "Datasheet" "https://www.ti.com/general/docs/suppproductinfo.tsp?distId=26&gotoUrl=https://www.ti.com/lit/gpn/tpd1e0b04"
			(at 0 0 90)
			(layer "F.Fab")
			(hide yes)
			(effects
				(font
					(size 1.27 1.27)
					(thickness 0.15)
				)
			)
		)
		(property "MPN" "TPD1E0B04DPYR"
			(at 253.53 -6.85 0)
			(layer "F.Fab")
			(hide yes)
			(effects
				(font
					(size 1 1)
					(thickness 0.15)
				)
			)
		)
		(property "Manufacturer" "Texas Instruments"
			(at 253.53 -6.85 0)
			(layer "F.Fab")
			(hide yes)
			(effects
				(font
					(size 1 1)
					(thickness 0.15)
				)
			)
		)
		(property "Author" "Antmicro"
			(at 253.53 -6.85 0)
			(layer "F.Fab")
			(hide yes)
			(effects
				(font
					(size 1 1)
					(thickness 0.15)
				)
			)
		)
		(property "License" "Apache-2.0"
			(at 253.53 -6.85 0)
			(layer "F.Fab")
			(hide yes)
			(effects
				(font
					(size 1 1)
					(thickness 0.15)
				)
			)
		)
		(sheetname "Peripherals")
		(sheetfile "peripherals.kicad_sch")
		(attr smd)
		(fp_rect
			(start -0.725 -0.475)
			(end 0.725 0.475)
			(stroke
				(width 0.05)
				(type solid)
			)
			(fill none)
			(layer "F.CrtYd")
		)
		(fp_rect
			(start -0.55 -0.35)
			(end 0.55 0.35)
			(stroke
				(width 0.15)
				(type solid)
			)
			(fill none)
			(layer "F.Fab")
		)
		(fp_text user "${REFERENCE}"
			(at -0.8 3.2 90)
			(layer "F.Fab")
			(hide yes)
			(effects
				(font
					(size 0.7 0.7)
					(thickness 0.15)
				)
				(justify left bottom)
			)
		)
		(fp_text user "License: Apache-2.0"
			(at -0.8 5.6 90)
			(layer "F.Fab")
			(hide yes)
			(effects
				(font
					(size 0.7 0.7)
					(thickness 0.15)
				)
				(justify left bottom)
			)
		)
		(fp_text user "Author: Antmicro"
			(at -0.8 4.4 90)
			(layer "F.Fab")
			(hide yes)
			(effects
				(font
					(size 0.7 0.7)
					(thickness 0.15)
				)
				(justify left bottom)
			)
		)
		(pad "1" smd roundrect
			(at -0.351 0 90)
			(size 0.3 0.5)
			(layers "F.Cu" "F.Paste" "F.Mask")
			(roundrect_rratio 0.25)
			(net 1 "GND")
			(pinfunction "C")
			(pintype "passive")
		)
		(pad "2" smd roundrect
			(at 0.349 0 90)
			(size 0.3 0.5)
			(layers "F.Cu" "F.Paste" "F.Mask")
			(roundrect_rratio 0.25)
			(net 659 "I2C1_SCL")
			(pinfunction "A")
			(pintype "passive")
		)
	)
	(footprint "antmicro-footprints:SOD-923"
		(layer "F.Cu")
		(at 53.725 117.4 180)
		(property "Reference" "D28"
			(at 2.75 -0.425 0)
			(unlocked yes)
			(layer "F.SilkS")
			(effects
				(font
					(size 0.7 0.7)
					(thickness 0.15)
				)
				(justify left bottom)
			)
		)
		(property "Value" "DF2S30FS_SOD"
			(at 0 1.3 180)
			(unlocked yes)
			(layer "F.Fab")
			(effects
				(font
					(size 0.7 0.7)
					(thickness 0.15)
				)
				(justify left bottom)
			)
		)
		(property "Footprint" "antmicro-footprints:SOD-923"
			(at 0 0 180)
			(layer "F.Fab")
			(hide yes)
			(effects
				(font
					(size 1.27 1.27)
					(thickness 0.15)
				)
			)
		)
		(property "Datasheet" "https://toshiba.semicon-storage.com/info/DF2S30FS_datasheet_en_20211216.pdf?did=11156&prodName=DF2S30FS"
			(at 0 0 180)
			(layer "F.Fab")
			(hide yes)
			(effects
				(font
					(size 1.27 1.27)
					(thickness 0.15)
				)
			)
		)
		(property "Author" "Antmicro"
			(at 107.45 234.8 0)
			(layer "F.Fab")
			(hide yes)
			(effects
				(font
					(size 1 1)
					(thickness 0.15)
				)
			)
		)
		(property "License" "Apache-2.0"
			(at 107.45 234.8 0)
			(layer "F.Fab")
			(hide yes)
			(effects
				(font
					(size 1 1)
					(thickness 0.15)
				)
			)
		)
		(property "MPN" "DF2S30FS"
			(at 107.45 234.8 0)
			(layer "F.Fab")
			(hide yes)
			(effects
				(font
					(size 1 1)
					(thickness 0.15)
				)
			)
		)
		(property "Manufacturer" "Toshiba"
			(at 107.45 234.8 0)
			(layer "F.Fab")
			(hide yes)
			(effects
				(font
					(size 1 1)
					(thickness 0.15)
				)
			)
		)
		(sheetname "Supply")
		(sheetfile "supply.kicad_sch")
		(attr smd)
		(fp_line
			(start 0.5 0.4)
			(end 0.5 0.3)
			(stroke
				(width 0.15)
				(type solid)
			)
			(layer "F.SilkS")
		)
		(fp_line
			(start 0.5 -0.4)
			(end 0.5 -0.3)
			(stroke
				(width 0.15)
				(type solid)
			)
			(layer "F.SilkS")
		)
		(fp_line
			(start -0.16 -0.4)
			(end -0.16 0.4)
			(stroke
				(width 0.15)
				(type solid)
			)
			(layer "F.SilkS")
		)
		(fp_line
			(start -0.5 0.4)
			(end 0.5 0.4)
			(stroke
				(width 0.15)
				(type solid)
			)
			(layer "F.SilkS")
		)
		(fp_line
			(start -0.5 0.4)
			(end -0.5 0.3)
			(stroke
				(width 0.15)
				(type solid)
			)
			(layer "F.SilkS")
		)
		(fp_line
			(start -0.5 -0.3)
			(end -0.5 -0.4)
			(stroke
				(width 0.15)
				(type solid)
			)
			(layer "F.SilkS")
		)
		(fp_line
			(start -0.5 -0.4)
			(end 0.5 -0.4)
			(stroke
				(width 0.15)
				(type solid)
			)
			(layer "F.SilkS")
		)
		(fp_rect
			(start -0.68 -0.41)
			(end 0.68 0.41)
			(stroke
				(width 0.05)
				(type solid)
			)
			(fill none)
			(layer "F.CrtYd")
		)
		(fp_line
			(start -0.202 -0.3)
			(end -0.202 0.298)
			(stroke
				(width 0.15)
				(type solid)
			)
			(layer "F.Fab")
		)
		(fp_rect
			(start -0.402 -0.3)
			(end 0.4 0.298)
			(stroke
				(width 0.15)
				(type solid)
			)
			(fill none)
			(layer "F.Fab")
		)
		(fp_text user "License: Apache-2.0"
			(at -0.68 4.5 180)
			(layer "F.Fab")
			(hide yes)
			(effects
				(font
					(size 0.7 0.7)
					(thickness 0.15)
				)
				(justify left bottom)
			)
		)
		(fp_text user "Author: Antmicro"
			(at -0.68 5.7 180)
			(layer "F.Fab")
			(hide yes)
			(effects
				(font
					(size 0.7 0.7)
					(thickness 0.15)
				)
				(justify left bottom)
			)
		)
		(fp_text user "${REFERENCE}"
			(at -0.68 3.3 180)
			(unlocked yes)
			(layer "F.Fab")
			(hide yes)
			(effects
				(font
					(size 0.7 0.7)
					(thickness 0.15)
				)
				(justify left bottom)
			)
		)
		(pad "1" smd roundrect
			(at -0.438 0 180)
			(size 0.4 0.325)
			(layers "F.Cu" "F.Paste" "F.Mask")
			(roundrect_rratio 0.25)
			(net 189 "Net-(D28-C)")
			(pinfunction "C")
			(pintype "passive")
		)
		(pad "2" smd roundrect
			(at 0.436 0 180)
			(size 0.4 0.325)
			(layers "F.Cu" "F.Paste" "F.Mask")
			(roundrect_rratio 0.25)
			(net 1 "GND")
			(pinfunction "A")
			(pintype "passive")
		)
	)
	(footprint "antmicro-footprints:R_0402_1005Metric"
		(layer "F.Cu")
		(at 79.23 85.88 90)
		(descr "Resistor SMD 0402")
		(tags "resistor SMD 0402")
		(property "Reference" "R177"
			(at 0.71 0.41 90)
			(layer "F.SilkS")
			(effects
				(font
					(size 0.7 0.7)
					(thickness 0.15)
				)
				(justify left bottom)
			)
		)
		(property "Value" "R_45k3_0402"
			(at -1.011843 1.772047 90)
			(layer "F.Fab")
			(effects
				(font
					(size 0.7 0.7)
					(thickness 0.15)
				)
				(justify left bottom)
			)
		)
		(property "Footprint" "antmicro-footprints:R_0402_1005Metric"
			(at 0 0 90)
			(layer "F.Fab")
			(hide yes)
			(effects
				(font
					(size 1.27 1.27)
					(thickness 0.15)
				)
			)
		)
		(property "Datasheet" "https://www.bourns.com/docs/product-datasheets/cr.pdf"
			(at 0 0 90)
			(layer "F.Fab")
			(hide yes)
			(effects
				(font
					(size 1.27 1.27)
					(thickness 0.15)
				)
			)
		)
		(property "Author" "Antmicro"
			(at 165.11 6.65 0)
			(layer "F.Fab")
			(hide yes)
			(effects
				(font
					(size 1 1)
					(thickness 0.15)
				)
			)
		)
		(property "License" "Apache-2.0"
			(at 165.11 6.65 0)
			(layer "F.Fab")
			(hide yes)
			(effects
				(font
					(size 1 1)
					(thickness 0.15)
				)
			)
		)
		(property "MPN" "CR0402-FX-4532GLF"
			(at 165.11 6.65 0)
			(layer "F.Fab")
			(hide yes)
			(effects
				(font
					(size 1 1)
					(thickness 0.15)
				)
			)
		)
		(property "Manufacturer" "Bourns"
			(at 165.11 6.65 0)
			(layer "F.Fab")
			(hide yes)
			(effects
				(font
					(size 1 1)
					(thickness 0.15)
				)
			)
		)
		(property "Tolerance" "1%"
			(at 165.11 6.65 0)
			(layer "F.Fab")
			(hide yes)
			(effects
				(font
					(size 1 1)
					(thickness 0.15)
				)
			)
		)
		(property "Val" "45k3"
			(at 165.11 6.65 0)
			(layer "F.Fab")
			(hide yes)
			(effects
				(font
					(size 1 1)
					(thickness 0.15)
				)
			)
		)
		(sheetname "Supply")
		(sheetfile "supply.kicad_sch")
		(attr smd)
		(fp_rect
			(start -0.925 -0.47)
			(end 0.925 0.47)
			(stroke
				(width 0.05)
				(type default)
			)
			(fill none)
			(layer "F.CrtYd")
		)
		(fp_rect
			(start -0.5 -0.25)
			(end 0.5 0.25)
			(stroke
				(width 0.15)
				(type solid)
			)
			(fill none)
			(layer "F.Fab")
		)
		(fp_text user "License: Apache-2.0"
			(at -0.95 5.169 90)
			(layer "F.Fab")
			(hide yes)
			(effects
				(font
					(size 0.7 0.7)
					(thickness 0.15)
				)
				(justify left bottom)
			)
		)
		(fp_text user "Author: Antmicro"
			(at -0.95 4.169 90)
			(layer "F.Fab")
			(hide yes)
			(effects
				(font
					(size 0.7 0.7)
					(thickness 0.15)
				)
				(justify left bottom)
			)
		)
		(fp_text user "${REFERENCE}"
			(at -0.95 3.168 90)
			(layer "F.Fab")
			(hide yes)
			(effects
				(font
					(size 0.7 0.7)
					(thickness 0.15)
				)
				(justify left bottom)
			)
		)
		(pad "1" smd roundrect
			(at -0.48 0 90)
			(size 0.59 0.64)
			(layers "F.Cu" "F.Paste" "F.Mask")
			(roundrect_rratio 0.25)
			(net 711 "/Supply/3V3_FB")
			(pintype "passive")
		)
		(pad "2" smd roundrect
			(at 0.48 0 90)
			(size 0.59 0.64)
			(layers "F.Cu" "F.Paste" "F.Mask")
			(roundrect_rratio 0.25)
			(net 641 "/Supply/3V3_OUT")
			(pintype "passive")
		)
	)
)
